(kicad_pcb
	(version 20241229)
	(generator "pcbnew")
	(generator_version "9.0")
	(general
		(thickness 1.6296)
		(legacy_teardrops no)
	)
	(paper "A3")
	(title_block
		(title "Thunderbolt to 10GbE adapter")
		(date "2026-04-21")
		(rev "1.1.0")
		(company "Antmicro Ltd")
		(comment 1 "www.antmicro.com")
		(comment 9 "footprints 96-100 of 703")
	)
	(layers
		(0 "F.Cu" signal)
		(4 "In1.Cu" signal)
		(6 "In2.Cu" signal)
		(8 "In3.Cu" signal)
		(10 "In4.Cu" signal)
		(12 "In5.Cu" signal)
		(14 "In6.Cu" signal)
		(2 "B.Cu" signal)
		(9 "F.Adhes" user "F.Adhesive")
		(11 "B.Adhes" user "B.Adhesive")
		(13 "F.Paste" user)
		(15 "B.Paste" user)
		(5 "F.SilkS" user "F.Silkscreen")
		(7 "B.SilkS" user "B.Silkscreen")
		(1 "F.Mask" user)
		(3 "B.Mask" user)
		(17 "Dwgs.User" user "User.Drawings")
		(19 "Cmts.User" user "User.Comments")
		(21 "Eco1.User" user "User.Eco1")
		(23 "Eco2.User" user "User.Eco2")
		(25 "Edge.Cuts" user)
		(27 "Margin" user)
		(31 "F.CrtYd" user "F.Courtyard")
		(29 "B.CrtYd" user "B.Courtyard")
		(35 "F.Fab" user)
		(33 "B.Fab" user)
	)
	(footprint "antmicro-footprints:R_0402_1005Metric"
		(layer "F.Cu")
		(at 151.55 112.150002)
		(descr "Resistor SMD 0402")
		(tags "resistor SMD 0402")
		(property "Reference" "R103"
			(at 14.149998 17.25 0)
			(layer "F.SilkS")
			(effects
				(font
					(size 0.7 0.7)
					(thickness 0.15)
				)
			)
		)
		(property "Value" "R_30k_0402"
			(at -1.011843 1.772047 0)
			(layer "F.Fab")
			(effects
				(font
					(size 0.7 0.7)
					(thickness 0.15)
				)
				(justify left bottom)
			)
		)
		(property "Datasheet" "https://www.bourns.com/docs/product-datasheets/cr.pdf"
			(at 0 0 0)
			(layer "F.Fab")
			(hide yes)
			(effects
				(font
					(size 1.27 1.27)
					(thickness 0.15)
				)
			)
		)
		(property "Description" "SMD Chip Resistor, 30 kohm, ± 1%, 63 mW, 0402 [1005 Metric], Thick Film, General Purpose"
			(at 0 0 0)
			(layer "F.Fab")
			(hide yes)
			(effects
				(font
					(size 1.27 1.27)
					(thickness 0.15)
				)
			)
		)
		(property "MPN" "CR0402-FX-3002GLF"
			(at 0 0 0)
			(unlocked yes)
			(layer "F.Fab")
			(hide yes)
			(effects
				(font
					(size 1 1)
					(thickness 0.15)
				)
			)
		)
		(property "Manufacturer" "Bourns"
			(at 0 0 0)
			(unlocked yes)
			(layer "F.Fab")
			(hide yes)
			(effects
				(font
					(size 1 1)
					(thickness 0.15)
				)
			)
		)
		(property "License" "Apache-2.0"
			(at 0 0 0)
			(unlocked yes)
			(layer "F.Fab")
			(hide yes)
			(effects
				(font
					(size 1 1)
					(thickness 0.15)
				)
			)
		)
		(property "Author" "Antmicro"
			(at 0 0 0)
			(unlocked yes)
			(layer "F.Fab")
			(hide yes)
			(effects
				(font
					(size 1 1)
					(thickness 0.15)
				)
			)
		)
		(property "Val" "30k"
			(at 0 0 0)
			(unlocked yes)
			(layer "F.Fab")
			(hide yes)
			(effects
				(font
					(size 1 1)
					(thickness 0.15)
				)
			)
		)
		(property "Tolerance" "1%"
			(at 0 0 0)
			(unlocked yes)
			(layer "F.Fab")
			(hide yes)
			(effects
				(font
					(size 1 1)
					(thickness 0.15)
				)
			)
		)
		(sheetname "/X710 DCDC converters/")
		(sheetfile "DCDC_converters_X710.kicad_sch")
		(attr smd)
		(fp_rect
			(start -0.925 -0.47)
			(end 0.925 0.47)
			(stroke
				(width 0.05)
				(type default)
			)
			(fill no)
			(layer "F.CrtYd")
		)
		(fp_rect
			(start -0.5 -0.25)
			(end 0.5 0.25)
			(stroke
				(width 0.15)
				(type solid)
			)
			(fill no)
			(layer "F.Fab")
		)
		(fp_text user "Author: Antmicro"
			(at -0.95 4.169 0)
			(layer "F.Fab")
			(effects
				(font
					(size 0.7 0.7)
					(thickness 0.15)
				)
				(justify left bottom)
			)
		)
		(fp_text user "License: Apache-2.0"
			(at -0.95 5.169 0)
			(layer "F.Fab")
			(effects
				(font
					(size 0.7 0.7)
					(thickness 0.15)
				)
				(justify left bottom)
			)
		)
		(fp_text user "${REFERENCE}"
			(at -0.95 3.168 0)
			(layer "F.Fab")
			(effects
				(font
					(size 0.7 0.7)
					(thickness 0.15)
				)
				(justify left bottom)
			)
		)
		(pad "1" smd roundrect
			(at -0.48 0)
			(size 0.59 0.64)
			(layers "F.Cu" "F.Mask" "F.Paste")
			(roundrect_rratio 0.25)
			(net 23 "GND")
			(pintype "passive")
		)
		(pad "2" smd roundrect
			(at 0.48 0)
			(size 0.59 0.64)
			(layers "F.Cu" "F.Mask" "F.Paste")
			(roundrect_rratio 0.25)
			(net 337 "/X710 DCDC converters/1V88_FB")
			(pintype "passive")
		)
	)
	(footprint "antmicro-footprints:C_0603_1608Metric_EIA"
		(layer "F.Cu")
		(at 140.105001 99.774999 -90)
		(descr "Capacitor SMD 0603, IPC-7351 Density Level A")
		(tags "Capacitor 0603")
		(property "Reference" "C257"
			(at -9.274999 -36.144999 270)
			(layer "F.SilkS")
			(effects
				(font
					(size 0.7 0.7)
					(thickness 0.15)
				)
			)
		)
		(property "Value" "C_22u_16V_0603"
			(at -1.42757 1.770288 270)
			(layer "F.Fab")
			(effects
				(font
					(size 0.7 0.7)
					(thickness 0.15)
				)
				(justify left bottom)
			)
		)
		(property "Datasheet" "https://product.samsungsem.com/mlcc/CL10A226MO7JZN.do"
			(at 0 0 270)
			(layer "F.Fab")
			(hide yes)
			(effects
				(font
					(size 1.27 1.27)
					(thickness 0.15)
				)
			)
		)
		(property "Description" "SMD Multilayer Ceramic Capacitor"
			(at 0 0 270)
			(layer "F.Fab")
			(hide yes)
			(effects
				(font
					(size 1.27 1.27)
					(thickness 0.15)
				)
			)
		)
		(property "MPN" "CL10A226MO7JZNC"
			(at 0 0 270)
			(unlocked yes)
			(layer "F.Fab")
			(hide yes)
			(effects
				(font
					(size 1 1)
					(thickness 0.15)
				)
			)
		)
		(property "Manufacturer" "Samsung Electro-Mechanics"
			(at 0 0 270)
			(unlocked yes)
			(layer "F.Fab")
			(hide yes)
			(effects
				(font
					(size 1 1)
					(thickness 0.15)
				)
			)
		)
		(property "License" "Apache-2.0"
			(at 0 0 270)
			(unlocked yes)
			(layer "F.Fab")
			(hide yes)
			(effects
				(font
					(size 1 1)
					(thickness 0.15)
				)
			)
		)
		(property "Author" "Antmicro"
			(at 0 0 270)
			(unlocked yes)
			(layer "F.Fab")
			(hide yes)
			(effects
				(font
					(size 1 1)
					(thickness 0.15)
				)
			)
		)
		(property "Val" "22u"
			(at 0 0 270)
			(unlocked yes)
			(layer "F.Fab")
			(hide yes)
			(effects
				(font
					(size 1 1)
					(thickness 0.15)
				)
			)
		)
		(property "Voltage" "16V"
			(at 0 0 270)
			(unlocked yes)
			(layer "F.Fab")
			(hide yes)
			(effects
				(font
					(size 1 1)
					(thickness 0.15)
				)
			)
		)
		(property "Dielectric" ""
			(at 0 0 270)
			(unlocked yes)
			(layer "F.Fab")
			(hide yes)
			(effects
				(font
					(size 1 1)
					(thickness 0.15)
				)
			)
		)
		(sheetname "/X710-AT2 power/")
		(sheetfile "x710-at2-power.kicad_sch")
		(attr smd)
		(fp_line
			(start -0.15 0.55)
			(end 0.15 0.55)
			(stroke
				(width 0.15)
				(type solid)
			)
			(layer "F.SilkS")
		)
		(fp_line
			(start -0.15 -0.55)
			(end 0.15 -0.55)
			(stroke
				(width 0.15)
				(type solid)
			)
			(layer "F.SilkS")
		)
		(fp_rect
			(start -1.25 -0.65)
			(end 1.25 0.65)
			(stroke
				(width 0.05)
				(type solid)
			)
			(fill no)
			(layer "F.CrtYd")
		)
		(fp_rect
			(start -0.8 -0.45)
			(end 0.8 0.45)
			(stroke
				(width 0.15)
				(type solid)
			)
			(fill no)
			(layer "F.Fab")
		)
		(fp_text user "${REFERENCE}"
			(at -1.682 3.895 270)
			(layer "F.Fab")
			(effects
				(font
					(size 0.7 0.7)
					(thickness 0.15)
				)
				(justify left bottom)
			)
		)
		(fp_text user "License: Apache-2.0"
			(at -1.682 5.895 270)
			(layer "F.Fab")
			(effects
				(font
					(size 0.7 0.7)
					(thickness 0.15)
				)
				(justify left bottom)
			)
		)
		(fp_text user "Author: Antmicro"
			(at -1.682 4.894 270)
			(layer "F.Fab")
			(effects
				(font
					(size 0.7 0.7)
					(thickness 0.15)
				)
				(justify left bottom)
			)
		)
		(pad "1" smd roundrect
			(at -0.7 0 270)
			(size 0.8 1.1)
			(layers "F.Cu" "F.Mask" "F.Paste")
			(roundrect_rratio 0.2)
			(net 23 "GND")
			(pintype "passive")
		)
		(pad "2" smd roundrect
			(at 0.7 0 270)
			(size 0.8 1.1)
			(layers "F.Cu" "F.Mask" "F.Paste")
			(roundrect_rratio 0.2)
			(net 9 "VCCD")
			(pintype "passive")
		)
	)
	(footprint "antmicro-footprints:LED_0603_1608Metric_G"
		(layer "F.Cu")
		(at 125 56.5 90)
		(descr "LED SMD 0603 Green")
		(tags "LED SMD 0603 Green")
		(property "Reference" "D16"
			(at -0.9 -0.8 90)
			(layer "F.SilkS")
			(effects
				(font
					(size 0.7 0.7)
					(thickness 0.15)
				)
				(justify left bottom)
			)
		)
		(property "Value" "LED_G_0603_LTST-C190GKT"
			(at -0.001 1.599 90)
			(layer "F.Fab")
			(effects
				(font
					(size 0.7 0.7)
					(thickness 0.15)
				)
				(justify left bottom)
			)
		)
		(property "Datasheet" "https://media.digikey.com/pdf/Data%20Sheets/Lite-On%20PDFs/LTST-C190GKT.pdf"
			(at 0 0 90)
			(layer "F.Fab")
			(hide yes)
			(effects
				(font
					(size 1.27 1.27)
					(thickness 0.15)
				)
			)
		)
		(property "Description" "LED, Green, SMD, 0603, 20 mA, 2.1 V, 569 nm"
			(at 0 0 90)
			(layer "F.Fab")
			(hide yes)
			(effects
				(font
					(size 1.27 1.27)
					(thickness 0.15)
				)
			)
		)
		(property "MPN" "LTST-C190GKT"
			(at 0 0 90)
			(unlocked yes)
			(layer "F.Fab")
			(hide yes)
			(effects
				(font
					(size 1 1)
					(thickness 0.15)
				)
			)
		)
		(property "Manufacturer" "Lite-On"
			(at 0 0 90)
			(unlocked yes)
			(layer "F.Fab")
			(hide yes)
			(effects
				(font
					(size 1 1)
					(thickness 0.15)
				)
			)
		)
		(property "Author" "Antmicro"
			(at 0 0 90)
			(unlocked yes)
			(layer "F.Fab")
			(hide yes)
			(effects
				(font
					(size 1 1)
					(thickness 0.15)
				)
			)
		)
		(property "License" "Apache-2.0"
			(at 0 0 90)
			(unlocked yes)
			(layer "F.Fab")
			(hide yes)
			(effects
				(font
					(size 1 1)
					(thickness 0.15)
				)
			)
		)
		(property "Color" "Green"
			(at 0 0 90)
			(unlocked yes)
			(layer "F.Fab")
			(hide yes)
			(effects
				(font
					(size 1 1)
					(thickness 0.15)
				)
			)
		)
		(sheetname "/Power input/")
		(sheetfile "power_input.kicad_sch")
		(attr smd)
		(fp_line
			(start 0.22 -0.35)
			(end -0.22 -0.35)
			(stroke
				(width 0.15)
				(type solid)
			)
			(layer "F.SilkS")
		)
		(fp_line
			(start -1.18 -0.319)
			(end -1.18 0.321)
			(stroke
				(width 0.15)
				(type solid)
			)
			(layer "F.SilkS")
		)
		(fp_line
			(start 0.105328 0.001008)
			(end 0.24 0.001)
			(stroke
				(width 0.1)
				(type solid)
			)
			(layer "F.SilkS")
		)
		(fp_line
			(start -0.094672 0.001008)
			(end 0.105328 -0.198992)
			(stroke
				(width 0.1)
				(type solid)
			)
			(layer "F.SilkS")
		)
		(fp_line
			(start -0.094672 0.001008)
			(end -0.24 0.001008)
			(stroke
				(width 0.1)
				(type solid)
			)
			(layer "F.SilkS")
		)
		(fp_line
			(start 0.105328 0.201008)
			(end 0.105328 -0.198992)
			(stroke
				(width 0.1)
				(type solid)
			)
			(layer "F.SilkS")
		)
		(fp_line
			(start 0.105328 0.201008)
			(end -0.094672 0.001008)
			(stroke
				(width 0.1)
				(type solid)
			)
			(layer "F.SilkS")
		)
		(fp_line
			(start -0.094672 0.201008)
			(end -0.094672 -0.198992)
			(stroke
				(width 0.1)
				(type solid)
			)
			(layer "F.SilkS")
		)
		(fp_line
			(start 0.22 0.35)
			(end -0.22 0.35)
			(stroke
				(width 0.15)
				(type solid)
			)
			(layer "F.SilkS")
		)
		(fp_rect
			(start 1.25 0.65)
			(end -1.25 -0.65)
			(stroke
				(width 0.05)
				(type solid)
			)
			(fill no)
			(layer "F.CrtYd")
		)
		(fp_line
			(start 0.201 -0.202)
			(end -0.101 0)
			(stroke
				(width 0.15)
				(type solid)
			)
			(layer "F.Fab")
		)
		(fp_line
			(start -0.199 -0.202)
			(end -0.199 0.1)
			(stroke
				(width 0.15)
				(type solid)
			)
			(layer "F.Fab")
		)
		(fp_line
			(start 0.599 0)
			(end 0.201 0)
			(stroke
				(width 0.15)
				(type solid)
			)
			(layer "F.Fab")
		)
		(fp_line
			(start 0.201 0)
			(end 0.201 -0.202)
			(stroke
				(width 0.15)
				(type solid)
			)
			(layer "F.Fab")
		)
		(fp_line
			(start -0.101 0)
			(end 0.201 0.2)
			(stroke
				(width 0.15)
				(type solid)
			)
			(layer "F.Fab")
		)
		(fp_line
			(start -0.199 0)
			(end -0.597 0)
			(stroke
				(width 0.15)
				(type solid)
			)
			(layer "F.Fab")
		)
		(fp_line
			(start 0.201 0.2)
			(end 0.201 0)
			(stroke
				(width 0.15)
				(type solid)
			)
			(layer "F.Fab")
		)
		(fp_line
			(start -0.199 0.2)
			(end -0.199 0.1)
			(stroke
				(width 0.15)
				(type solid)
			)
			(layer "F.Fab")
		)
		(fp_rect
			(start 0.848 0.4)
			(end -0.85 -0.402)
			(stroke
				(width 0.15)
				(type solid)
			)
			(fill no)
			(layer "F.Fab")
		)
		(fp_text user "${REFERENCE}"
			(at -1.4224 5.999 90)
			(layer "F.Fab")
			(effects
				(font
					(size 0.7 0.7)
					(thickness 0.15)
				)
				(justify left bottom)
			)
		)
		(fp_text user "Author: Antmicro"
			(at -1.4224 4.799 90)
			(layer "F.Fab")
			(effects
				(font
					(size 0.7 0.7)
					(thickness 0.15)
				)
				(justify left bottom)
			)
		)
		(fp_text user "License: Apache-2.0"
			(at -1.4224 3.599 90)
			(layer "F.Fab")
			(effects
				(font
					(size 0.7 0.7)
					(thickness 0.15)
				)
				(justify left bottom)
			)
		)
		(pad "1" smd roundrect
			(at -0.7 0 270)
			(size 0.8 1)
			(layers "F.Cu" "F.Mask" "F.Paste")
			(roundrect_rratio 0.2)
			(net 23 "GND")
			(pinfunction "C")
			(pintype "passive")
		)
		(pad "2" smd roundrect
			(at 0.7 0 270)
			(size 0.8 1)
			(layers "F.Cu" "F.Mask" "F.Paste")
			(roundrect_rratio 0.2)
			(net 420 "Net-(D16-A)")
			(pinfunction "A")
			(pintype "passive")
		)
	)
	(footprint "antmicro-footprints:C_0603_1608Metric_EIA"
		(layer "F.Cu")
		(at 133.304999 89.274998 -90)
		(descr "Capacitor SMD 0603, IPC-7351 Density Level A")
		(tags "Capacitor 0603")
		(property "Reference" "C258"
			(at 4.225001 16.054999 270)
			(layer "F.SilkS")
			(effects
				(font
					(size 0.7 0.7)
					(thickness 0.15)
				)
				(justify left bottom)
			)
		)
		(property "Value" "C_22u_16V_0603"
			(at -1.42757 1.770288 270)
			(layer "F.Fab")
			(effects
				(font
					(size 0.7 0.7)
					(thickness 0.15)
				)
				(justify left bottom)
			)
		)
		(property "Datasheet" "https://product.samsungsem.com/mlcc/CL10A226MO7JZN.do"
			(at 0 0 270)
			(layer "F.Fab")
			(hide yes)
			(effects
				(font
					(size 1.27 1.27)
					(thickness 0.15)
				)
			)
		)
		(property "Description" "SMD Multilayer Ceramic Capacitor"
			(at 0 0 270)
			(layer "F.Fab")
			(hide yes)
			(effects
				(font
					(size 1.27 1.27)
					(thickness 0.15)
				)
			)
		)
		(property "MPN" "CL10A226MO7JZNC"
			(at 0 0 270)
			(unlocked yes)
			(layer "F.Fab")
			(hide yes)
			(effects
				(font
					(size 1 1)
					(thickness 0.15)
				)
			)
		)
		(property "Manufacturer" "Samsung Electro-Mechanics"
			(at 0 0 270)
			(unlocked yes)
			(layer "F.Fab")
			(hide yes)
			(effects
				(font
					(size 1 1)
					(thickness 0.15)
				)
			)
		)
		(property "License" "Apache-2.0"
			(at 0 0 270)
			(unlocked yes)
			(layer "F.Fab")
			(hide yes)
			(effects
				(font
					(size 1 1)
					(thickness 0.15)
				)
			)
		)
		(property "Author" "Antmicro"
			(at 0 0 270)
			(unlocked yes)
			(layer "F.Fab")
			(hide yes)
			(effects
				(font
					(size 1 1)
					(thickness 0.15)
				)
			)
		)
		(property "Val" "22u"
			(at 0 0 270)
			(unlocked yes)
			(layer "F.Fab")
			(hide yes)
			(effects
				(font
					(size 1 1)
					(thickness 0.15)
				)
			)
		)
		(property "Voltage" "16V"
			(at 0 0 270)
			(unlocked yes)
			(layer "F.Fab")
			(hide yes)
			(effects
				(font
					(size 1 1)
					(thickness 0.15)
				)
			)
		)
		(property "Dielectric" ""
			(at 0 0 270)
			(unlocked yes)
			(layer "F.Fab")
			(hide yes)
			(effects
				(font
					(size 1 1)
					(thickness 0.15)
				)
			)
		)
		(sheetname "/X710-AT2 power/")
		(sheetfile "x710-at2-power.kicad_sch")
		(attr smd)
		(fp_line
			(start -0.15 0.55)
			(end 0.15 0.55)
			(stroke
				(width 0.15)
				(type solid)
			)
			(layer "F.SilkS")
		)
		(fp_line
			(start -0.15 -0.55)
			(end 0.15 -0.55)
			(stroke
				(width 0.15)
				(type solid)
			)
			(layer "F.SilkS")
		)
		(fp_rect
			(start -1.25 -0.65)
			(end 1.25 0.65)
			(stroke
				(width 0.05)
				(type solid)
			)
			(fill no)
			(layer "F.CrtYd")
		)
		(fp_rect
			(start -0.8 -0.45)
			(end 0.8 0.45)
			(stroke
				(width 0.15)
				(type solid)
			)
			(fill no)
			(layer "F.Fab")
		)
		(fp_text user "License: Apache-2.0"
			(at -1.682 5.895 270)
			(layer "F.Fab")
			(effects
				(font
					(size 0.7 0.7)
					(thickness 0.15)
				)
				(justify left bottom)
			)
		)
		(fp_text user "Author: Antmicro"
			(at -1.682 4.894 270)
			(layer "F.Fab")
			(effects
				(font
					(size 0.7 0.7)
					(thickness 0.15)
				)
				(justify left bottom)
			)
		)
		(fp_text user "${REFERENCE}"
			(at -1.682 3.895 270)
			(layer "F.Fab")
			(effects
				(font
					(size 0.7 0.7)
					(thickness 0.15)
				)
				(justify left bottom)
			)
		)
		(pad "1" smd roundrect
			(at -0.7 0 270)
			(size 0.8 1.1)
			(layers "F.Cu" "F.Mask" "F.Paste")
			(roundrect_rratio 0.2)
			(net 23 "GND")
			(pintype "passive")
		)
		(pad "2" smd roundrect
			(at 0.7 0 270)
			(size 0.8 1.1)
			(layers "F.Cu" "F.Mask" "F.Paste")
			(roundrect_rratio 0.2)
			(net 7 "+3V3")
			(pintype "passive")
		)
	)
	(footprint "antmicro-footprints:MP_Pad6mm_Drill3.2mm"
		(layer "F.Cu")
		(at 172 64 90)
		(property "Reference" "MP8"
			(at -4.25 -1.25 180)
			(layer "F.SilkS")
			(effects
				(font
					(size 0.7 0.7)
					(thickness 0.15)
				)
				(justify left bottom)
			)
		)
		(property "Value" "MP_Pad6mm_Drill3.2mm"
			(at 0 3.9 90)
			(layer "F.Fab")
			(effects
				(font
					(size 0.7 0.7)
					(thickness 0.15)
				)
				(justify left bottom)
			)
		)
		(property "Description" "Mechanical part"
			(at 0 0 90)
			(layer "F.Fab")
			(hide yes)
			(effects
				(font
					(size 1.27 1.27)
					(thickness 0.15)
				)
			)
		)
		(property "Author" "Antmicro"
			(at 0 0 90)
			(unlocked yes)
			(layer "F.Fab")
			(hide yes)
			(effects
				(font
					(size 1 1)
					(thickness 0.15)
				)
			)
		)
		(property "License" "Apache-2.0"
			(at 0 0 90)
			(unlocked yes)
			(layer "F.Fab")
			(hide yes)
			(effects
				(font
					(size 1 1)
					(thickness 0.15)
				)
			)
		)
		(sheetname "/")
		(sheetfile "thunderbolt-to-10gbe-adapter.kicad_sch")
		(attr exclude_from_pos_files exclude_from_bom)
		(fp_circle
			(center 0 0)
			(end 3.25 0)
			(stroke
				(width 0.05)
				(type default)
			)
			(fill no)
			(layer "F.CrtYd")
		)
		(fp_text user "Author: Antmicro"
			(at -0.178 7.225 90)
			(layer "F.Fab")
			(effects
				(font
					(size 0.7 0.7)
					(thickness 0.15)
				)
				(justify left bottom)
			)
		)
		(fp_text user "License: Apache-2.0"
			(at -0.178 8.425 90)
			(layer "F.Fab")
			(effects
				(font
					(size 0.7 0.7)
					(thickness 0.15)
				)
				(justify left bottom)
			)
		)
		(fp_text user "${REFERENCE}"
			(at -0.178 6.025 90)
			(layer "F.Fab")
			(effects
				(font
					(size 0.7 0.7)
					(thickness 0.15)
				)
				(justify left bottom)
			)
		)
		(pad "1" thru_hole circle
			(at 0 0 90)
			(size 6 6)
			(drill 3.2)
			(layers "*.Cu" "*.Mask")
			(remove_unused_layers no)
			(net 23 "GND")
			(pintype "passive")
		)
	)
)
